# SCM (Grand Teton) — schematic netlist excerpt (pin names and nets, part order shuffled) for the footprints in the layout excerpt that follows; sources: Cadence DE-HDL packaged netlist, KiCad conversion of 12092022_DA0F0TMDCD0_F0T_Management_Board_D_brd_V3_OCP.brd

C105  Q_CAP  0.1UF 25V 10% X7R  pkg 0402  page 16 : A = P1V8_AUX ; B = GND
C65  Q_CAP  0.1UF 25V 10% X7R  pkg 0402  page 17 : A = P3V3_STBY_PLLAHVDD ; B = GND

(kicad_pcb
	(version 20260206)
	(generator "pcbnew")
	(generator_version "10.0")
	(general
		(thickness 1.6)
		(legacy_teardrops no)
	)
	(paper "A4")
	(title_block
		(title "12092022_DA0F0TMDCD0_F0T_Management_Board_D_brd_V3_OCP.brd")
		(comment 1 "Grand Teton / footprints 1243-1244 of 1440")
	)
	(layers
		(0 "F.Cu" signal "TOP")
		(4 "In1.Cu" signal "GND")
		(6 "In2.Cu" signal "IN1")
		(8 "In3.Cu" signal "GND1")
		(10 "In4.Cu" signal "IN2")
		(12 "In5.Cu" signal "VCC")
		(14 "In6.Cu" signal "VCC1")
		(16 "In7.Cu" signal "IN3")
		(18 "In8.Cu" signal "GND2")
		(20 "In9.Cu" signal "IN4")
		(22 "In10.Cu" signal "GND3")
		(2 "B.Cu" signal "BOTTOM")
		(9 "F.Adhes" user "F.Adhesive")
		(11 "B.Adhes" user "B.Adhesive")
		(13 "F.Paste" user "Package Geometry/Pastemask Top")
		(15 "B.Paste" user "Package Geometry/Pastemask Bottom")
		(5 "F.SilkS" user "Ref Des/Silkscreen Top")
		(7 "B.SilkS" user "Ref Des/Silkscreen Bottom")
		(1 "F.Mask" user "Board Geometry/Soldermask Top")
		(3 "B.Mask" user "Board Geometry/Soldermask Bottom")
		(17 "Dwgs.User" user "User.Drawings")
		(19 "Cmts.User" user "User.Comments")
		(21 "Eco1.User" user "User.Eco1")
		(23 "Eco2.User" user "User.Eco2")
		(25 "Edge.Cuts" user "Board Geometry/Outline")
		(27 "Margin" user)
		(31 "F.CrtYd" user "Package Geometry/Place Bound Top")
		(29 "B.CrtYd" user "Package Geometry/Place Bound Bottom")
		(35 "F.Fab" user "Ref Des/Assembly Top")
		(33 "B.Fab" user "Ref Des/Assembly Bottom")
	)
	(footprint ""
		(layer "B.Cu")
		(at 60.440316 -45.029628 -90)
		(property "Reference" "C105"
			(at 0 0 90)
			(layer "B.SilkS")
			(hide yes)
			(effects
				(font
					(size 1.27 1.27)
				)
				(justify mirror)
			)
		)
		(property "Value" ""
			(at 0 0 90)
			(layer "B.Fab")
			(effects
				(font
					(size 1.27 1.27)
				)
				(justify mirror)
			)
		)
		(duplicate_pad_numbers_are_jumpers no)
		(fp_line
			(start -0.7874 0.4064)
			(end 0.7874 0.4064)
			(stroke
				(width 0.1524)
				(type default)
			)
			(layer "B.SilkS")
		)
		(fp_line
			(start 0.7874 0.4064)
			(end 0.7874 -0.4064)
			(stroke
				(width 0.1524)
				(type default)
			)
			(layer "B.SilkS")
		)
		(fp_line
			(start -0.7874 -0.4064)
			(end -0.7874 0.4064)
			(stroke
				(width 0.1524)
				(type default)
			)
			(layer "B.SilkS")
		)
		(fp_line
			(start 0.7874 -0.4064)
			(end -0.7874 -0.4064)
			(stroke
				(width 0.1524)
				(type default)
			)
			(layer "B.SilkS")
		)
		(fp_line
			(start -0.67945 0.3048)
			(end -0.120396 0.3048)
			(stroke
				(width 0.1)
				(type default)
			)
			(layer "B.Fab")
		)
		(fp_line
			(start -0.120396 0.3048)
			(end -0.120396 0.2794)
			(stroke
				(width 0.1)
				(type default)
			)
			(layer "B.Fab")
		)
		(fp_line
			(start 0.12065 0.3048)
			(end 0.67945 0.3048)
			(stroke
				(width 0.1)
				(type default)
			)
			(layer "B.Fab")
		)
		(fp_line
			(start 0.67945 0.3048)
			(end 0.67945 -0.305054)
			(stroke
				(width 0.1)
				(type default)
			)
			(layer "B.Fab")
		)
		(fp_line
			(start -0.120396 0.2794)
			(end 0.12065 0.2794)
			(stroke
				(width 0.1)
				(type default)
			)
			(layer "B.Fab")
		)
		(fp_line
			(start 0.12065 0.2794)
			(end 0.12065 0.3048)
			(stroke
				(width 0.1)
				(type default)
			)
			(layer "B.Fab")
		)
		(fp_line
			(start -0.12065 -0.2794)
			(end -0.12065 -0.3048)
			(stroke
				(width 0.1)
				(type default)
			)
			(layer "B.Fab")
		)
		(fp_line
			(start 0.12065 -0.2794)
			(end -0.12065 -0.2794)
			(stroke
				(width 0.1)
				(type default)
			)
			(layer "B.Fab")
		)
		(fp_line
			(start -0.67945 -0.3048)
			(end -0.67945 0.3048)
			(stroke
				(width 0.1)
				(type default)
			)
			(layer "B.Fab")
		)
		(fp_line
			(start -0.12065 -0.3048)
			(end -0.67945 -0.3048)
			(stroke
				(width 0.1)
				(type default)
			)
			(layer "B.Fab")
		)
		(fp_line
			(start 0.12065 -0.305054)
			(end 0.12065 -0.2794)
			(stroke
				(width 0.1)
				(type default)
			)
			(layer "B.Fab")
		)
		(fp_line
			(start 0.67945 -0.305054)
			(end 0.12065 -0.305054)
			(stroke
				(width 0.1)
				(type default)
			)
			(layer "B.Fab")
		)
		(pad "1" smd circle
			(at 0.40005 0 90)
			(size 0 0)
			(layers "B.Cu" "B.Mask" "B.Paste")
			(net "P1V8_AUX")
		)
		(pad "2" smd circle
			(at -0.40005 0 90)
			(size 0 0)
			(layers "B.Cu" "B.Mask" "B.Paste")
			(net "GND")
		)
	)
	(footprint ""
		(layer "B.Cu")
		(at 54.736492 -43.358054 90)
		(property "Reference" "C65"
			(at 0 0 90)
			(layer "B.SilkS")
			(hide yes)
			(effects
				(font
					(size 1.27 1.27)
				)
				(justify mirror)
			)
		)
		(property "Value" ""
			(at 0 0 90)
			(layer "B.Fab")
			(effects
				(font
					(size 1.27 1.27)
				)
				(justify mirror)
			)
		)
		(duplicate_pad_numbers_are_jumpers no)
		(fp_line
			(start 0.7874 -0.4064)
			(end -0.7874 -0.4064)
			(stroke
				(width 0.1524)
				(type default)
			)
			(layer "B.SilkS")
		)
		(fp_line
			(start -0.7874 -0.4064)
			(end -0.7874 0.4064)
			(stroke
				(width 0.1524)
				(type default)
			)
			(layer "B.SilkS")
		)
		(fp_line
			(start 0.7874 0.4064)
			(end 0.7874 -0.4064)
			(stroke
				(width 0.1524)
				(type default)
			)
			(layer "B.SilkS")
		)
		(fp_line
			(start -0.7874 0.4064)
			(end 0.7874 0.4064)
			(stroke
				(width 0.1524)
				(type default)
			)
			(layer "B.SilkS")
		)
		(fp_line
			(start 0.67945 -0.305054)
			(end 0.12065 -0.305054)
			(stroke
				(width 0.1)
				(type default)
			)
			(layer "B.Fab")
		)
		(fp_line
			(start 0.12065 -0.305054)
			(end 0.12065 -0.2794)
			(stroke
				(width 0.1)
				(type default)
			)
			(layer "B.Fab")
		)
		(fp_line
			(start -0.12065 -0.3048)
			(end -0.67945 -0.3048)
			(stroke
				(width 0.1)
				(type default)
			)
			(layer "B.Fab")
		)
		(fp_line
			(start -0.67945 -0.3048)
			(end -0.67945 0.3048)
			(stroke
				(width 0.1)
				(type default)
			)
			(layer "B.Fab")
		)
		(fp_line
			(start 0.12065 -0.2794)
			(end -0.12065 -0.2794)
			(stroke
				(width 0.1)
				(type default)
			)
			(layer "B.Fab")
		)
		(fp_line
			(start -0.12065 -0.2794)
			(end -0.12065 -0.3048)
			(stroke
				(width 0.1)
				(type default)
			)
			(layer "B.Fab")
		)
		(fp_line
			(start 0.12065 0.2794)
			(end 0.12065 0.3048)
			(stroke
				(width 0.1)
				(type default)
			)
			(layer "B.Fab")
		)
		(fp_line
			(start -0.120396 0.2794)
			(end 0.12065 0.2794)
			(stroke
				(width 0.1)
				(type default)
			)
			(layer "B.Fab")
		)
		(fp_line
			(start 0.67945 0.3048)
			(end 0.67945 -0.305054)
			(stroke
				(width 0.1)
				(type default)
			)
			(layer "B.Fab")
		)
		(fp_line
			(start 0.12065 0.3048)
			(end 0.67945 0.3048)
			(stroke
				(width 0.1)
				(type default)
			)
			(layer "B.Fab")
		)
		(fp_line
			(start -0.120396 0.3048)
			(end -0.120396 0.2794)
			(stroke
				(width 0.1)
				(type default)
			)
			(layer "B.Fab")
		)
		(fp_line
			(start -0.67945 0.3048)
			(end -0.120396 0.3048)
			(stroke
				(width 0.1)
				(type default)
			)
			(layer "B.Fab")
		)
		(pad "1" smd circle
			(at 0.40005 0 270)
			(size 0 0)
			(layers "B.Cu" "B.Mask" "B.Paste")
			(net "P3V3_STBY_PLLAHVDD")
		)
		(pad "2" smd circle
			(at -0.40005 0 270)
			(size 0 0)
			(layers "B.Cu" "B.Mask" "B.Paste")
			(net "GND")
		)
	)
)
